(kicad_pcb
	(version 20260206)
	(generator "pcbnew")
	(generator_version "10.0")
	(general
		(thickness 1.6)
		(legacy_teardrops no)
	)
	(paper "A4")
	(title_block
		(title "03242023_DA0F0TMBIJ0_F0T_Motherboard_J_brd_V01_OCP.brd")
		(comment 1 "Grand Teton / footprint 1682 of 6105 (U1), pads 3901-4000 of 4677")
	)
	(layers
		(0 "F.Cu" signal "TOP")
		(4 "In1.Cu" signal "GND")
		(6 "In2.Cu" signal "IN1")
		(8 "In3.Cu" signal "GND1")
		(10 "In4.Cu" signal "IN2")
		(12 "In5.Cu" signal "GND2")
		(14 "In6.Cu" signal "IN3")
		(16 "In7.Cu" signal "GND3")
		(18 "In8.Cu" signal "VCC")
		(20 "In9.Cu" signal "VCC1")
		(22 "In10.Cu" signal "GND4")
		(24 "In11.Cu" signal "IN4")
		(26 "In12.Cu" signal "GND5")
		(28 "In13.Cu" signal "IN5")
		(30 "In14.Cu" signal "GND6")
		(32 "In15.Cu" signal "IN6")
		(34 "In16.Cu" signal "GND7")
		(2 "B.Cu" signal "BOTTOM")
		(9 "F.Adhes" user "F.Adhesive")
		(11 "B.Adhes" user "B.Adhesive")
		(13 "F.Paste" user "Package Geometry/Pastemask Top")
		(15 "B.Paste" user "Package Geometry/Pastemask Bottom")
		(5 "F.SilkS" user "Ref Des/Silkscreen Top")
		(7 "B.SilkS" user "Ref Des/Silkscreen Bottom")
		(1 "F.Mask" user "Board Geometry/Soldermask Top")
		(3 "B.Mask" user "Board Geometry/Soldermask Bottom")
		(17 "Dwgs.User" user "User.Drawings")
		(19 "Cmts.User" user "User.Comments")
		(21 "Eco1.User" user "User.Eco1")
		(23 "Eco2.User" user "User.Eco2")
		(25 "Edge.Cuts" user "Board Geometry/Outline")
		(27 "Margin" user)
		(31 "F.CrtYd" user "Package Geometry/Place Bound Top")
		(29 "B.CrtYd" user "Package Geometry/Place Bound Bottom")
		(35 "F.Fab" user "Ref Des/Assembly Top")
		(33 "B.Fab" user "Ref Des/Assembly Bottom")
	)
	(footprint ""
		(layer "F.Cu")
		(at 111.93018 -251.76988 90)
		(property "Reference" "U1"
			(at -74.913236 41.548812 0)
			(unlocked yes)
			(layer "F.SilkS")
			(effects
				(font
					(size 1.6002 1.1938)
					(thickness 0.1524)
				)
				(justify left)
			)
		)
		(property "Value" ""
			(at 0 0 90)
			(layer "F.Fab")
			(effects
				(font
					(size 1.27 1.27)
				)
			)
		)
		(duplicate_pad_numbers_are_jumpers no)
		(pad "EN84" smd oval
			(at 31.727902 25.664414 315)
			(size 0.381 0.4826)
			(drill
				(offset 0 -0.0508)
			)
			(layers "F.Cu" "F.Mask" "F.Paste")
			(net "PVCCFA_EHV_FIVRA_CPU1")
		)
		(pad "EN86" smd oval
			(at 33.355534 25.664414 315)
			(size 0.381 0.4826)
			(drill
				(offset 0 -0.0508)
			)
			(layers "F.Cu" "F.Mask" "F.Paste")
			(net "Net_713")
		)
		(pad "EN88" smd oval
			(at 34.98342 25.664414 315)
			(size 0.381 0.4826)
			(drill
				(offset 0 -0.0508)
			)
			(layers "F.Cu" "F.Mask" "F.Paste")
			(net "GND")
		)
		(pad "EP4" smd oval
			(at -34.98342 26.024586 225)
			(size 0.381 0.4826)
			(drill
				(offset 0 -0.0508)
			)
			(layers "F.Cu" "F.Mask" "F.Paste")
			(net "M_G_CPU1_SB_DQ<30>")
		)
		(pad "EP6" smd oval
			(at -33.355534 26.024586 225)
			(size 0.381 0.4826)
			(drill
				(offset 0 -0.0508)
			)
			(layers "F.Cu" "F.Mask" "F.Paste")
			(net "M_G_CPU1_SB_DQS_DN<3>")
		)
		(pad "EP8" smd oval
			(at -31.727902 26.024586 225)
			(size 0.381 0.4826)
			(drill
				(offset 0 -0.0508)
			)
			(layers "F.Cu" "F.Mask" "F.Paste")
			(net "M_G_CPU1_SB_DQ<26>")
		)
		(pad "EP10" smd circle
			(at -30.100016 26.024586 270)
			(size 0.4318 0.4318)
			(layers "F.Cu" "F.Mask" "F.Paste")
			(net "M_F_CPU1_SB_DQ<23>")
		)
		(pad "EP12" smd circle
			(at -28.472384 26.024586 270)
			(size 0.4318 0.4318)
			(layers "F.Cu" "F.Mask" "F.Paste")
			(net "M_F_CPU1_SB_DQS_DP<7>")
		)
		(pad "EP14" smd circle
			(at -26.844498 26.024586 270)
			(size 0.4318 0.4318)
			(layers "F.Cu" "F.Mask" "F.Paste")
			(net "M_F_CPU1_SB_DQ<18>")
		)
		(pad "EP16" smd circle
			(at -25.216612 26.024586 270)
			(size 0.4318 0.4318)
			(layers "F.Cu" "F.Mask" "F.Paste")
			(net "M_E_CPU1_SB_DQ<31>")
		)
		(pad "EP18" smd circle
			(at -23.58898 26.024586 270)
			(size 0.4318 0.4318)
			(layers "F.Cu" "F.Mask" "F.Paste")
			(net "M_E_CPU1_SB_DQS_DP<8>")
		)
		(pad "EP20" smd circle
			(at -21.961094 26.024586 270)
			(size 0.4318 0.4318)
			(layers "F.Cu" "F.Mask" "F.Paste")
			(net "M_E_CPU1_SB_DQ<26>")
		)
		(pad "EP22" smd circle
			(at -20.333462 26.024586 270)
			(size 0.4318 0.4318)
			(layers "F.Cu" "F.Mask" "F.Paste")
			(net "M_E_CPU1_SB_DQ<23>")
		)
		(pad "EP24" smd circle
			(at -18.705576 26.024586 270)
			(size 0.4318 0.4318)
			(layers "F.Cu" "F.Mask" "F.Paste")
			(net "M_E_CPU1_SB_DQS_DP<7>")
		)
		(pad "EP26" smd circle
			(at -17.07769 26.024586 270)
			(size 0.4318 0.4318)
			(layers "F.Cu" "F.Mask" "F.Paste")
			(net "M_E_CPU1_SB_DQ<18>")
		)
		(pad "EP28" smd circle
			(at -15.450058 26.024586 270)
			(size 0.4318 0.4318)
			(layers "F.Cu" "F.Mask" "F.Paste")
			(net "M_E_CPU1_SB_DQ<15>")
		)
		(pad "EP30" smd circle
			(at -13.822426 26.024586 270)
			(size 0.4318 0.4318)
			(layers "F.Cu" "F.Mask" "F.Paste")
			(net "M_E_CPU1_SB_DQS_DP<6>")
		)
		(pad "EP32" smd circle
			(at -12.19454 26.024586 270)
			(size 0.4318 0.4318)
			(layers "F.Cu" "F.Mask" "F.Paste")
			(net "M_E_CPU1_SB_DQ<10>")
		)
		(pad "EP34" smd circle
			(at -10.566654 26.024586 270)
			(size 0.4318 0.4318)
			(layers "F.Cu" "F.Mask" "F.Paste")
			(net "M_E_CPU1_SB_CB<3>")
		)
		(pad "EP36" smd circle
			(at -8.939022 26.024586 270)
			(size 0.4318 0.4318)
			(layers "F.Cu" "F.Mask" "F.Paste")
			(net "M_E_CPU1_SB_DQS_DP<4>")
		)
		(pad "EP38" smd circle
			(at -7.311136 26.024586 270)
			(size 0.4318 0.4318)
			(layers "F.Cu" "F.Mask" "F.Paste")
			(net "M_E_CPU1_SB_CB<6>")
		)
		(pad "EP40" smd circle
			(at -5.68325 26.024586 270)
			(size 0.4318 0.4318)
			(layers "F.Cu" "F.Mask" "F.Paste")
			(net "M_E_CPU1_SB_CS_N<0>")
		)
		(pad "EP42" smd circle
			(at -4.055618 26.024586 270)
			(size 0.4318 0.4318)
			(layers "F.Cu" "F.Mask" "F.Paste")
			(net "M_E_CPU1_SB_PAR")
		)
		(pad "EP44" smd oval
			(at -2.427732 26.024586 270)
			(size 0.381 0.4826)
			(drill
				(offset 0 -0.0508)
			)
			(layers "F.Cu" "F.Mask" "F.Paste")
			(net "M_E_CPU1_SB_CA<3>")
		)
		(pad "EP47" smd oval
			(at 1.613916 26.134314 270)
			(size 0.381 0.4826)
			(drill
				(offset 0 -0.0508)
			)
			(layers "F.Cu" "F.Mask" "F.Paste")
			(net "M_E_CPU1_SA_CA<5>")
		)
		(pad "EP49" smd circle
			(at 3.241802 26.134314 270)
			(size 0.4318 0.4318)
			(layers "F.Cu" "F.Mask" "F.Paste")
			(net "M_E_CPU1_SA_CA<0>")
		)
		(pad "EP51" smd circle
			(at 4.869434 26.134314 270)
			(size 0.4318 0.4318)
			(layers "F.Cu" "F.Mask" "F.Paste")
			(net "M_E_CPU1_SA_CS_N<0>")
		)
		(pad "EP53" smd circle
			(at 6.49732 26.134314 270)
			(size 0.4318 0.4318)
			(layers "F.Cu" "F.Mask" "F.Paste")
			(net "M_E_CPU1_SA_CB<7>")
		)
		(pad "EP55" smd circle
			(at 8.124952 26.134314 270)
			(size 0.4318 0.4318)
			(layers "F.Cu" "F.Mask" "F.Paste")
			(net "M_E_CPU1_SA_DQS_DP<9>")
		)
		(pad "EP57" smd circle
			(at 9.752838 26.134314 270)
			(size 0.4318 0.4318)
			(layers "F.Cu" "F.Mask" "F.Paste")
			(net "M_E_CPU1_SA_CB<2>")
		)
		(pad "EP59" smd circle
			(at 11.380724 26.134314 270)
			(size 0.4318 0.4318)
			(layers "F.Cu" "F.Mask" "F.Paste")
			(net "M_E_CPU1_SA_DQ<31>")
		)
		(pad "EP61" smd circle
			(at 13.008356 26.134314 270)
			(size 0.4318 0.4318)
			(layers "F.Cu" "F.Mask" "F.Paste")
			(net "M_E_CPU1_SA_DQS_DP<8>")
		)
		(pad "EP63" smd circle
			(at 14.635988 26.134314 270)
			(size 0.4318 0.4318)
			(layers "F.Cu" "F.Mask" "F.Paste")
			(net "M_E_CPU1_SA_DQ<26>")
		)
		(pad "EP65" smd circle
			(at 16.263874 26.134314 270)
			(size 0.4318 0.4318)
			(layers "F.Cu" "F.Mask" "F.Paste")
			(net "M_E_CPU1_SA_DQ<23>")
		)
		(pad "EP67" smd circle
			(at 17.89176 26.134314 270)
			(size 0.4318 0.4318)
			(layers "F.Cu" "F.Mask" "F.Paste")
			(net "GND")
		)
		(pad "EP69" smd circle
			(at 19.519392 26.134314 270)
			(size 0.4318 0.4318)
			(layers "F.Cu" "F.Mask" "F.Paste")
			(net "GND")
		)
		(pad "EP71" smd circle
			(at 21.147278 26.134314 270)
			(size 0.4318 0.4318)
			(layers "F.Cu" "F.Mask" "F.Paste")
			(net "GND")
		)
		(pad "EP73" smd circle
			(at 22.77491 26.134314 270)
			(size 0.4318 0.4318)
			(layers "F.Cu" "F.Mask" "F.Paste")
			(net "M_E_CPU1_SA_DQ<6>")
		)
		(pad "EP75" smd circle
			(at 24.402796 26.134314 270)
			(size 0.4318 0.4318)
			(layers "F.Cu" "F.Mask" "F.Paste")
			(net "M_E_CPU1_SA_DQS_DN<0>")
		)
		(pad "EP77" smd circle
			(at 26.030682 26.134314 270)
			(size 0.4318 0.4318)
			(layers "F.Cu" "F.Mask" "F.Paste")
			(net "GND")
		)
		(pad "EP79" smd circle
			(at 27.658314 26.134314 270)
			(size 0.4318 0.4318)
			(layers "F.Cu" "F.Mask" "F.Paste")
			(net "M_E_CPU1_SA_DQ<2>")
		)
		(pad "EP81" smd circle
			(at 29.2862 26.134314 270)
			(size 0.4318 0.4318)
			(layers "F.Cu" "F.Mask" "F.Paste")
			(net "GND")
		)
		(pad "EP83" smd oval
			(at 30.914086 26.134314 315)
			(size 0.381 0.4826)
			(drill
				(offset 0 -0.0508)
			)
			(layers "F.Cu" "F.Mask" "F.Paste")
			(net "GND")
		)
		(pad "EP85" smd oval
			(at 32.541718 26.134314 315)
			(size 0.381 0.4826)
			(drill
				(offset 0 -0.0508)
			)
			(layers "F.Cu" "F.Mask" "F.Paste")
			(net "Net_737")
		)
		(pad "EP87" smd oval
			(at 34.169604 26.134314 315)
			(size 0.381 0.4826)
			(drill
				(offset 0 -0.0508)
			)
			(layers "F.Cu" "F.Mask" "F.Paste")
			(net "Net_708")
		)
		(pad "ER5" smd oval
			(at -34.169604 26.494486 225)
			(size 0.381 0.4826)
			(drill
				(offset 0 -0.0508)
			)
			(layers "F.Cu" "F.Mask" "F.Paste")
			(net "GND")
		)
		(pad "ER7" smd oval
			(at -32.541718 26.494486 225)
			(size 0.381 0.4826)
			(drill
				(offset 0 -0.0508)
			)
			(layers "F.Cu" "F.Mask" "F.Paste")
			(net "GND")
		)
		(pad "ER9" smd oval
			(at -30.914086 26.494486 225)
			(size 0.381 0.4826)
			(drill
				(offset 0 -0.0508)
			)
			(layers "F.Cu" "F.Mask" "F.Paste")
			(net "GND")
		)
		(pad "ER11" smd circle
			(at -29.2862 26.494486 270)
			(size 0.4318 0.4318)
			(layers "F.Cu" "F.Mask" "F.Paste")
			(net "M_F_CPU1_SB_DQ<22>")
		)
		(pad "ER13" smd circle
			(at -27.658314 26.494486 270)
			(size 0.4318 0.4318)
			(layers "F.Cu" "F.Mask" "F.Paste")
			(net "M_F_CPU1_SB_DQ<19>")
		)
		(pad "ER15" smd circle
			(at -26.030682 26.494486 270)
			(size 0.4318 0.4318)
			(layers "F.Cu" "F.Mask" "F.Paste")
			(net "GND")
		)
		(pad "ER17" smd circle
			(at -24.402796 26.494486 270)
			(size 0.4318 0.4318)
			(layers "F.Cu" "F.Mask" "F.Paste")
			(net "M_E_CPU1_SB_DQ<30>")
		)
		(pad "ER19" smd circle
			(at -22.77491 26.494486 270)
			(size 0.4318 0.4318)
			(layers "F.Cu" "F.Mask" "F.Paste")
			(net "M_E_CPU1_SB_DQ<27>")
		)
		(pad "ER21" smd circle
			(at -21.147278 26.494486 270)
			(size 0.4318 0.4318)
			(layers "F.Cu" "F.Mask" "F.Paste")
			(net "GND")
		)
		(pad "ER23" smd circle
			(at -19.519392 26.494486 270)
			(size 0.4318 0.4318)
			(layers "F.Cu" "F.Mask" "F.Paste")
			(net "M_E_CPU1_SB_DQ<22>")
		)
		(pad "ER25" smd circle
			(at -17.89176 26.494486 270)
			(size 0.4318 0.4318)
			(layers "F.Cu" "F.Mask" "F.Paste")
			(net "M_E_CPU1_SB_DQ<19>")
		)
		(pad "ER27" smd circle
			(at -16.263874 26.494486 270)
			(size 0.4318 0.4318)
			(layers "F.Cu" "F.Mask" "F.Paste")
			(net "GND")
		)
		(pad "ER29" smd circle
			(at -14.635988 26.494486 270)
			(size 0.4318 0.4318)
			(layers "F.Cu" "F.Mask" "F.Paste")
			(net "M_E_CPU1_SB_DQ<14>")
		)
		(pad "ER31" smd circle
			(at -13.008356 26.494486 270)
			(size 0.4318 0.4318)
			(layers "F.Cu" "F.Mask" "F.Paste")
			(net "M_E_CPU1_SB_DQ<11>")
		)
		(pad "ER33" smd circle
			(at -11.380724 26.494486 270)
			(size 0.4318 0.4318)
			(layers "F.Cu" "F.Mask" "F.Paste")
			(net "GND")
		)
		(pad "ER35" smd circle
			(at -9.752838 26.494486 270)
			(size 0.4318 0.4318)
			(layers "F.Cu" "F.Mask" "F.Paste")
			(net "M_E_CPU1_SB_CB<2>")
		)
		(pad "ER37" smd circle
			(at -8.124952 26.494486 270)
			(size 0.4318 0.4318)
			(layers "F.Cu" "F.Mask" "F.Paste")
			(net "M_E_CPU1_SB_CB<7>")
		)
		(pad "ER39" smd circle
			(at -6.49732 26.494486 270)
			(size 0.4318 0.4318)
			(layers "F.Cu" "F.Mask" "F.Paste")
			(net "GND")
		)
		(pad "ER41" smd circle
			(at -4.869434 26.494486 270)
			(size 0.4318 0.4318)
			(layers "F.Cu" "F.Mask" "F.Paste")
			(net "GND")
		)
		(pad "ER43" smd oval
			(at -3.241802 26.494486 270)
			(size 0.381 0.4826)
			(drill
				(offset 0 -0.0508)
			)
			(layers "F.Cu" "F.Mask" "F.Paste")
			(net "GND")
		)
		(pad "ER48" smd oval
			(at 2.427732 26.604468 270)
			(size 0.381 0.4826)
			(drill
				(offset 0 -0.0508)
			)
			(layers "F.Cu" "F.Mask" "F.Paste")
			(net "GND")
		)
		(pad "ER50" smd circle
			(at 4.055618 26.604468 270)
			(size 0.4318 0.4318)
			(layers "F.Cu" "F.Mask" "F.Paste")
			(net "GND")
		)
		(pad "ER52" smd circle
			(at 5.68325 26.604468 270)
			(size 0.4318 0.4318)
			(layers "F.Cu" "F.Mask" "F.Paste")
			(net "GND")
		)
		(pad "ER54" smd circle
			(at 7.311136 26.604468 270)
			(size 0.4318 0.4318)
			(layers "F.Cu" "F.Mask" "F.Paste")
			(net "M_E_CPU1_SA_CB<6>")
		)
		(pad "ER56" smd circle
			(at 8.939022 26.604468 270)
			(size 0.4318 0.4318)
			(layers "F.Cu" "F.Mask" "F.Paste")
			(net "M_E_CPU1_SA_CB<3>")
		)
		(pad "ER58" smd circle
			(at 10.566654 26.604468 270)
			(size 0.4318 0.4318)
			(layers "F.Cu" "F.Mask" "F.Paste")
			(net "GND")
		)
		(pad "ER60" smd circle
			(at 12.19454 26.604468 270)
			(size 0.4318 0.4318)
			(layers "F.Cu" "F.Mask" "F.Paste")
			(net "M_E_CPU1_SA_DQ<30>")
		)
		(pad "ER62" smd oval
			(at 13.822426 26.604468 270)
			(size 0.381 0.4826)
			(drill
				(offset 0 -0.0508)
			)
			(layers "F.Cu" "F.Mask" "F.Paste")
			(net "M_E_CPU1_SA_DQ<27>")
		)
		(pad "ER64" smd oval
			(at 15.450058 26.604468 270)
			(size 0.381 0.4826)
			(drill
				(offset 0 -0.0508)
			)
			(layers "F.Cu" "F.Mask" "F.Paste")
			(net "GND")
		)
		(pad "ER66" smd oval
			(at 17.07769 26.604468 270)
			(size 0.381 0.4826)
			(drill
				(offset 0 -0.0508)
			)
			(layers "F.Cu" "F.Mask" "F.Paste")
			(net "M_E_CPU1_SA_DQ<20>")
		)
		(pad "ER68" smd oval
			(at 18.705576 26.604468 270)
			(size 0.381 0.4826)
			(drill
				(offset 0 -0.0508)
			)
			(layers "F.Cu" "F.Mask" "F.Paste")
			(net "M_E_CPU1_SA_DQ<19>")
		)
		(pad "ER70" smd oval
			(at 20.333462 26.604468 270)
			(size 0.381 0.4826)
			(drill
				(offset 0 -0.0508)
			)
			(layers "F.Cu" "F.Mask" "F.Paste")
			(net "GND")
		)
		(pad "ER72" smd oval
			(at 21.961094 26.604468 270)
			(size 0.381 0.4826)
			(drill
				(offset 0 -0.0508)
			)
			(layers "F.Cu" "F.Mask" "F.Paste")
			(net "M_E_CPU1_SA_DQ<7>")
		)
		(pad "ER74" smd oval
			(at 23.58898 26.604468 270)
			(size 0.381 0.4826)
			(drill
				(offset 0 -0.0508)
			)
			(layers "F.Cu" "F.Mask" "F.Paste")
			(net "GND")
		)
		(pad "ER76" smd oval
			(at 25.216612 26.604468 270)
			(size 0.381 0.4826)
			(drill
				(offset 0 -0.0508)
			)
			(layers "F.Cu" "F.Mask" "F.Paste")
			(net "M_E_CPU1_SA_DQ<3>")
		)
		(pad "ER78" smd oval
			(at 26.844498 26.604468 270)
			(size 0.381 0.4826)
			(drill
				(offset 0 -0.0508)
			)
			(layers "F.Cu" "F.Mask" "F.Paste")
			(net "GND")
		)
		(pad "ER80" smd oval
			(at 28.472384 26.604468 270)
			(size 0.381 0.4826)
			(drill
				(offset 0 -0.0508)
			)
			(layers "F.Cu" "F.Mask" "F.Paste")
			(net "GND")
		)
		(pad "ER82" smd oval
			(at 30.100016 26.604468 315)
			(size 0.381 0.4826)
			(drill
				(offset 0 -0.0508)
			)
			(layers "F.Cu" "F.Mask" "F.Paste")
			(net "GND")
		)
		(pad "ER84" smd oval
			(at 31.727902 26.604468 315)
			(size 0.381 0.4826)
			(drill
				(offset 0 -0.0508)
			)
			(layers "F.Cu" "F.Mask" "F.Paste")
			(net "GND")
		)
		(pad "ER86" smd oval
			(at 33.355534 26.604468 315)
			(size 0.381 0.4826)
			(drill
				(offset 0 -0.0508)
			)
			(layers "F.Cu" "F.Mask" "F.Paste")
			(net "GND")
		)
		(pad "ET8" smd oval
			(at -31.727902 26.964132 225)
			(size 0.381 0.4826)
			(drill
				(offset 0 -0.0508)
			)
			(layers "F.Cu" "F.Mask" "F.Paste")
			(net "M_G_CPU1_SB_DQ<27>")
		)
		(pad "ET10" smd oval
			(at -30.100016 26.964132 225)
			(size 0.381 0.4826)
			(drill
				(offset 0 -0.0508)
			)
			(layers "F.Cu" "F.Mask" "F.Paste")
			(net "GND")
		)
		(pad "ET12" smd oval
			(at -28.472384 26.964132 270)
			(size 0.381 0.4826)
			(drill
				(offset 0 -0.0508)
			)
			(layers "F.Cu" "F.Mask" "F.Paste")
			(net "M_F_CPU1_SB_DQS_DN<7>")
		)
		(pad "ET14" smd oval
			(at -26.844498 26.964132 270)
			(size 0.381 0.4826)
			(drill
				(offset 0 -0.0508)
			)
			(layers "F.Cu" "F.Mask" "F.Paste")
			(net "GND")
		)
		(pad "ET16" smd oval
			(at -25.216612 26.964132 270)
			(size 0.381 0.4826)
			(drill
				(offset 0 -0.0508)
			)
			(layers "F.Cu" "F.Mask" "F.Paste")
			(net "GND")
		)
		(pad "ET18" smd oval
			(at -23.58898 26.964132 270)
			(size 0.381 0.4826)
			(drill
				(offset 0 -0.0508)
			)
			(layers "F.Cu" "F.Mask" "F.Paste")
			(net "M_E_CPU1_SB_DQS_DN<8>")
		)
		(pad "ET20" smd oval
			(at -21.961094 26.964132 270)
			(size 0.381 0.4826)
			(drill
				(offset 0 -0.0508)
			)
			(layers "F.Cu" "F.Mask" "F.Paste")
			(net "GND")
		)
		(pad "ET22" smd oval
			(at -20.333462 26.964132 270)
			(size 0.381 0.4826)
			(drill
				(offset 0 -0.0508)
			)
			(layers "F.Cu" "F.Mask" "F.Paste")
			(net "GND")
		)
		(pad "ET24" smd oval
			(at -18.705576 26.964132 270)
			(size 0.381 0.4826)
			(drill
				(offset 0 -0.0508)
			)
			(layers "F.Cu" "F.Mask" "F.Paste")
			(net "M_E_CPU1_SB_DQS_DN<7>")
		)
		(pad "ET26" smd oval
			(at -17.07769 26.964132 270)
			(size 0.381 0.4826)
			(drill
				(offset 0 -0.0508)
			)
			(layers "F.Cu" "F.Mask" "F.Paste")
			(net "GND")
		)
		(pad "ET28" smd oval
			(at -15.450058 26.964132 270)
			(size 0.381 0.4826)
			(drill
				(offset 0 -0.0508)
			)
			(layers "F.Cu" "F.Mask" "F.Paste")
			(net "GND")
		)
		(pad "ET30" smd oval
			(at -13.822426 26.964132 270)
			(size 0.381 0.4826)
			(drill
				(offset 0 -0.0508)
			)
			(layers "F.Cu" "F.Mask" "F.Paste")
			(net "M_E_CPU1_SB_DQS_DN<6>")
		)
		(pad "ET32" smd oval
			(at -12.19454 26.964132 270)
			(size 0.381 0.4826)
			(drill
				(offset 0 -0.0508)
			)
			(layers "F.Cu" "F.Mask" "F.Paste")
			(net "GND")
		)
		(pad "ET34" smd oval
			(at -10.566654 26.964132 270)
			(size 0.381 0.4826)
			(drill
				(offset 0 -0.0508)
			)
			(layers "F.Cu" "F.Mask" "F.Paste")
			(net "GND")
		)
		(pad "ET36" smd oval
			(at -8.939022 26.964132 270)
			(size 0.381 0.4826)
			(drill
				(offset 0 -0.0508)
			)
			(layers "F.Cu" "F.Mask" "F.Paste")
			(net "M_E_CPU1_SB_DQS_DN<4>")
		)
	)
)
